(kicad_pcb
	(version 20260206)
	(generator "pcbnew")
	(generator_version "10.0")
	(general
		(thickness 1.6)
		(legacy_teardrops no)
	)
	(paper "A4")
	(title_block
		(title "04192023_DAF0TMB3IC0_F0TG_MB_C_brd_V02_OCP.brd")
		(comment 1 "Grand Teton / footprints 381-386 of 8354")
	)
	(layers
		(0 "F.Cu" signal "TOP")
		(4 "In1.Cu" signal "GND")
		(6 "In2.Cu" signal "IN1")
		(8 "In3.Cu" signal "GND1")
		(10 "In4.Cu" signal "IN2")
		(12 "In5.Cu" signal "GND2")
		(14 "In6.Cu" signal "IN3")
		(16 "In7.Cu" signal "GND3")
		(18 "In8.Cu" signal "VCC")
		(20 "In9.Cu" signal "VCC1")
		(22 "In10.Cu" signal "GND4")
		(24 "In11.Cu" signal "IN4")
		(26 "In12.Cu" signal "GND5")
		(28 "In13.Cu" signal "IN5")
		(30 "In14.Cu" signal "GND6")
		(32 "In15.Cu" signal "IN6")
		(34 "In16.Cu" signal "GND7")
		(2 "B.Cu" signal "BOTTOM")
		(9 "F.Adhes" user "F.Adhesive")
		(11 "B.Adhes" user "B.Adhesive")
		(13 "F.Paste" user "Package Geometry/Pastemask Top")
		(15 "B.Paste" user "Package Geometry/Pastemask Bottom")
		(5 "F.SilkS" user "Ref Des/Silkscreen Top")
		(7 "B.SilkS" user "Ref Des/Silkscreen Bottom")
		(1 "F.Mask" user "Board Geometry/Soldermask Top")
		(3 "B.Mask" user "Board Geometry/Soldermask Bottom")
		(17 "Dwgs.User" user "User.Drawings")
		(19 "Cmts.User" user "User.Comments")
		(21 "Eco1.User" user "User.Eco1")
		(23 "Eco2.User" user "User.Eco2")
		(25 "Edge.Cuts" user "Board Geometry/Outline")
		(27 "Margin" user)
		(31 "F.CrtYd" user "Package Geometry/Place Bound Top")
		(29 "B.CrtYd" user "Package Geometry/Place Bound Bottom")
		(35 "F.Fab" user "Ref Des/Assembly Top")
		(33 "B.Fab" user "Ref Des/Assembly Bottom")
	)
	(footprint ""
		(layer "F.Cu")
		(at 391.83945 -140.024612 90)
		(property "Reference" "U29"
			(at 0.762 2.00787 90)
			(unlocked yes)
			(layer "F.SilkS")
			(effects
				(font
					(size 0.7874 0.5842)
					(thickness 0.1524)
				)
			)
		)
		(property "Value" ""
			(at 0 0 90)
			(layer "F.Fab")
			(effects
				(font
					(size 1.27 1.27)
				)
			)
		)
		(duplicate_pad_numbers_are_jumpers no)
		(fp_line
			(start 1.7272 -1.1176)
			(end 0.254 -1.1176)
			(stroke
				(width 0.1524)
				(type default)
			)
			(layer "F.SilkS")
		)
		(fp_line
			(start 1.7272 -1.1176)
			(end 1.7272 1.1176)
			(stroke
				(width 0.1524)
				(type default)
			)
			(layer "F.SilkS")
		)
		(fp_line
			(start 0.254 -1.1176)
			(end 0 -0.7366)
			(stroke
				(width 0.1524)
				(type default)
			)
			(layer "F.SilkS")
		)
		(fp_line
			(start -0.254 -1.1176)
			(end -1.7272 -1.1176)
			(stroke
				(width 0.1524)
				(type default)
			)
			(layer "F.SilkS")
		)
		(fp_line
			(start 0 -0.7366)
			(end -0.254 -1.1176)
			(stroke
				(width 0.1524)
				(type default)
			)
			(layer "F.SilkS")
		)
		(fp_line
			(start 1.7272 1.1176)
			(end -1.7272 1.1176)
			(stroke
				(width 0.1524)
				(type default)
			)
			(layer "F.SilkS")
		)
		(fp_line
			(start -1.7272 1.1176)
			(end -1.7272 -1.1176)
			(stroke
				(width 0.1524)
				(type default)
			)
			(layer "F.SilkS")
		)
		(fp_poly
			(pts
				(xy -0.735076 -2.056638) (xy -1.116076 -1.294638) (xy -1.497076 -2.056638)
			)
			(stroke
				(width 0)
				(type default)
			)
			(fill yes)
			(layer "F.SilkS")
		)
		(fp_line
			(start 1.5748 -1.1176)
			(end -1.5748 -1.1176)
			(stroke
				(width 0.1)
				(type default)
			)
			(layer "F.Fab")
		)
		(fp_line
			(start -1.5748 -1.1176)
			(end -1.5748 1.1176)
			(stroke
				(width 0.1)
				(type default)
			)
			(layer "F.Fab")
		)
		(fp_line
			(start 1.5748 1.1176)
			(end 1.5748 -1.1176)
			(stroke
				(width 0.1)
				(type default)
			)
			(layer "F.Fab")
		)
		(fp_line
			(start -1.5748 1.1176)
			(end 1.5748 1.1176)
			(stroke
				(width 0.1)
				(type default)
			)
			(layer "F.Fab")
		)
		(fp_poly
			(pts
				(xy -1.9558 -0.649986) (xy -2.7178 -0.268986) (xy -2.7178 -1.030986)
			)
			(stroke
				(width 0)
				(type default)
			)
			(fill yes)
			(layer "F.Fab")
		)
		(pad "1" smd rect
			(at -0.999998 -0.649986)
			(size 0.3556 1.1176)
			(layers "F.Cu" "F.Mask" "F.Paste")
			(net "PWRGD_CPU0_PWROK")
		)
		(pad "2" smd rect
			(at -0.999998 0)
			(size 0.3556 1.1176)
			(layers "F.Cu" "F.Mask" "F.Paste")
			(net "GND")
		)
		(pad "3" smd rect
			(at -0.999998 0.649986)
			(size 0.3556 1.1176)
			(layers "F.Cu" "F.Mask" "F.Paste")
			(net "PWRGD_CPU0_PWROK")
		)
		(pad "4" smd rect
			(at 0.999998 0.649986)
			(size 0.3556 1.1176)
			(layers "F.Cu" "F.Mask" "F.Paste")
			(net "PVDDCR_CPU1_P0_RESET_N")
		)
		(pad "5" smd rect
			(at 0.999998 0)
			(size 0.3556 1.1176)
			(layers "F.Cu" "F.Mask" "F.Paste")
			(net "P1V8_AUX")
		)
		(pad "6" smd rect
			(at 0.999998 -0.649986)
			(size 0.3556 1.1176)
			(layers "F.Cu" "F.Mask" "F.Paste")
			(net "PVDDCR_CPU0_P0_RESET_N")
		)
	)
	(footprint ""
		(layer "F.Cu")
		(at 396.279878 -321.148202 90)
		(property "Reference" "R417"
			(at 0 0 90)
			(layer "F.SilkS")
			(hide yes)
			(effects
				(font
					(size 1.27 1.27)
				)
			)
		)
		(property "Value" ""
			(at 0 0 90)
			(layer "F.Fab")
			(effects
				(font
					(size 1.27 1.27)
				)
			)
		)
		(duplicate_pad_numbers_are_jumpers no)
		(fp_line
			(start 0.7874 -0.4064)
			(end 0.7874 0.4064)
			(stroke
				(width 0.1524)
				(type default)
			)
			(layer "F.SilkS")
		)
		(fp_line
			(start -0.7874 -0.4064)
			(end 0.7874 -0.4064)
			(stroke
				(width 0.1524)
				(type default)
			)
			(layer "F.SilkS")
		)
		(fp_line
			(start 0.7874 0.4064)
			(end -0.7874 0.4064)
			(stroke
				(width 0.1524)
				(type default)
			)
			(layer "F.SilkS")
		)
		(fp_line
			(start -0.7874 0.4064)
			(end -0.7874 -0.4064)
			(stroke
				(width 0.1524)
				(type default)
			)
			(layer "F.SilkS")
		)
		(fp_line
			(start -0.12065 -0.305054)
			(end -0.12065 -0.2794)
			(stroke
				(width 0.1)
				(type default)
			)
			(layer "F.Fab")
		)
		(fp_line
			(start -0.67945 -0.305054)
			(end -0.12065 -0.305054)
			(stroke
				(width 0.1)
				(type default)
			)
			(layer "F.Fab")
		)
		(fp_line
			(start 0.67945 -0.3048)
			(end 0.67945 0.3048)
			(stroke
				(width 0.1)
				(type default)
			)
			(layer "F.Fab")
		)
		(fp_line
			(start 0.12065 -0.3048)
			(end 0.67945 -0.3048)
			(stroke
				(width 0.1)
				(type default)
			)
			(layer "F.Fab")
		)
		(fp_line
			(start 0.12065 -0.2794)
			(end 0.12065 -0.3048)
			(stroke
				(width 0.1)
				(type default)
			)
			(layer "F.Fab")
		)
		(fp_line
			(start -0.12065 -0.2794)
			(end 0.12065 -0.2794)
			(stroke
				(width 0.1)
				(type default)
			)
			(layer "F.Fab")
		)
		(fp_line
			(start 0.120396 0.2794)
			(end -0.12065 0.2794)
			(stroke
				(width 0.1)
				(type default)
			)
			(layer "F.Fab")
		)
		(fp_line
			(start -0.12065 0.2794)
			(end -0.12065 0.3048)
			(stroke
				(width 0.1)
				(type default)
			)
			(layer "F.Fab")
		)
		(fp_line
			(start 0.67945 0.3048)
			(end 0.120396 0.3048)
			(stroke
				(width 0.1)
				(type default)
			)
			(layer "F.Fab")
		)
		(fp_line
			(start 0.120396 0.3048)
			(end 0.120396 0.2794)
			(stroke
				(width 0.1)
				(type default)
			)
			(layer "F.Fab")
		)
		(fp_line
			(start -0.12065 0.3048)
			(end -0.67945 0.3048)
			(stroke
				(width 0.1)
				(type default)
			)
			(layer "F.Fab")
		)
		(fp_line
			(start -0.67945 0.3048)
			(end -0.67945 -0.305054)
			(stroke
				(width 0.1)
				(type default)
			)
			(layer "F.Fab")
		)
		(pad "1" smd circle
			(at -0.40005 0 90)
			(size 0 0)
			(layers "F.Cu" "F.Mask" "F.Paste")
			(net "CPU0_THERMTRIP_N")
		)
		(pad "2" smd circle
			(at 0.40005 0 90)
			(size 0 0)
			(layers "F.Cu" "F.Mask" "F.Paste")
			(net "PVDD18_S5_P0")
		)
	)
	(footprint ""
		(layer "F.Cu")
		(at 147.199096 -65.321434 180)
		(property "Reference" "R1619"
			(at 0 0 180)
			(layer "F.SilkS")
			(hide yes)
			(effects
				(font
					(size 1.27 1.27)
				)
			)
		)
		(property "Value" ""
			(at 0 0 180)
			(layer "F.Fab")
			(effects
				(font
					(size 1.27 1.27)
				)
			)
		)
		(duplicate_pad_numbers_are_jumpers no)
		(fp_line
			(start 0.7874 0.4064)
			(end -0.7874 0.4064)
			(stroke
				(width 0.1524)
				(type default)
			)
			(layer "F.SilkS")
		)
		(fp_line
			(start 0.7874 -0.4064)
			(end 0.7874 0.4064)
			(stroke
				(width 0.1524)
				(type default)
			)
			(layer "F.SilkS")
		)
		(fp_line
			(start -0.7874 0.4064)
			(end -0.7874 -0.4064)
			(stroke
				(width 0.1524)
				(type default)
			)
			(layer "F.SilkS")
		)
		(fp_line
			(start -0.7874 -0.4064)
			(end 0.7874 -0.4064)
			(stroke
				(width 0.1524)
				(type default)
			)
			(layer "F.SilkS")
		)
		(fp_line
			(start 0.67945 0.3048)
			(end 0.120396 0.3048)
			(stroke
				(width 0.1)
				(type default)
			)
			(layer "F.Fab")
		)
		(fp_line
			(start 0.67945 -0.3048)
			(end 0.67945 0.3048)
			(stroke
				(width 0.1)
				(type default)
			)
			(layer "F.Fab")
		)
		(fp_line
			(start 0.12065 -0.2794)
			(end 0.12065 -0.3048)
			(stroke
				(width 0.1)
				(type default)
			)
			(layer "F.Fab")
		)
		(fp_line
			(start 0.12065 -0.3048)
			(end 0.67945 -0.3048)
			(stroke
				(width 0.1)
				(type default)
			)
			(layer "F.Fab")
		)
		(fp_line
			(start 0.120396 0.3048)
			(end 0.120396 0.2794)
			(stroke
				(width 0.1)
				(type default)
			)
			(layer "F.Fab")
		)
		(fp_line
			(start 0.120396 0.2794)
			(end -0.12065 0.2794)
			(stroke
				(width 0.1)
				(type default)
			)
			(layer "F.Fab")
		)
		(fp_line
			(start -0.12065 0.3048)
			(end -0.67945 0.3048)
			(stroke
				(width 0.1)
				(type default)
			)
			(layer "F.Fab")
		)
		(fp_line
			(start -0.12065 0.2794)
			(end -0.12065 0.3048)
			(stroke
				(width 0.1)
				(type default)
			)
			(layer "F.Fab")
		)
		(fp_line
			(start -0.12065 -0.2794)
			(end 0.12065 -0.2794)
			(stroke
				(width 0.1)
				(type default)
			)
			(layer "F.Fab")
		)
		(fp_line
			(start -0.12065 -0.305054)
			(end -0.12065 -0.2794)
			(stroke
				(width 0.1)
				(type default)
			)
			(layer "F.Fab")
		)
		(fp_line
			(start -0.67945 0.3048)
			(end -0.67945 -0.305054)
			(stroke
				(width 0.1)
				(type default)
			)
			(layer "F.Fab")
		)
		(fp_line
			(start -0.67945 -0.305054)
			(end -0.12065 -0.305054)
			(stroke
				(width 0.1)
				(type default)
			)
			(layer "F.Fab")
		)
		(pad "1" smd circle
			(at -0.40005 0 180)
			(size 0 0)
			(layers "F.Cu" "F.Mask" "F.Paste")
			(net "JTAG_BMC_OE")
		)
		(pad "2" smd circle
			(at 0.40005 0 180)
			(size 0 0)
			(layers "F.Cu" "F.Mask" "F.Paste")
			(net "JTAG_BMC_R_D_OE")
		)
	)
	(footprint ""
		(layer "F.Cu")
		(at 92.387674 -165.962076 180)
		(property "Reference" "PC273"
			(at -0.974852 -2.775204 0)
			(unlocked yes)
			(layer "F.SilkS")
			(effects
				(font
					(size 0.7874 0.5842)
					(thickness 0.1524)
				)
				(justify left)
			)
		)
		(property "Value" ""
			(at 0 0 180)
			(layer "F.Fab")
			(effects
				(font
					(size 1.27 1.27)
				)
			)
		)
		(duplicate_pad_numbers_are_jumpers no)
		(fp_line
			(start -3.400044 1.249934)
			(end 3.400044 1.249934)
			(stroke
				(width 0.1524)
				(type default)
			)
			(layer "F.SilkS")
		)
		(fp_circle
			(center 0 1.249934)
			(end -3.400044 1.249934)
			(stroke
				(width 0.1524)
				(type default)
			)
			(fill no)
			(layer "F.SilkS")
		)
		(fp_poly
			(pts
				(arc
					(start 3.400044 1.249934)
					(mid 0 4.649978)
					(end -3.400044 1.249934)
				)
			)
			(stroke
				(width 0)
				(type default)
			)
			(fill yes)
			(layer "F.SilkS")
		)
		(fp_circle
			(center 0 1.249934)
			(end -3.400044 1.249934)
			(stroke
				(width 0.1)
				(type default)
			)
			(fill no)
			(layer "F.Fab")
		)
		(pad "1" thru_hole rect
			(at 0 0 180)
			(size 1.524 1.524)
			(drill 1.016)
			(layers "*.Cu" "*.Mask")
			(remove_unused_layers no)
			(net "SW_P12V_AUX_PVDDCR_CPU0_P1_FLT")
			(clearance 0)
			(padstack
				(mode front_inner_back)
				(layer "Inner"
					(shape circle)
					(size 1.524 1.524)
					(clearance 0)
				)
				(layer "B.Cu"
					(shape rect)
					(size 1.524 1.524)
					(clearance 0)
				)
			)
		)
		(pad "2" thru_hole circle
			(at 0 2.500122 180)
			(size 1.524 1.524)
			(drill 1.016)
			(layers "*.Cu" "*.Mask")
			(remove_unused_layers no)
			(net "GND")
			(clearance 0)
		)
	)
	(footprint ""
		(layer "F.Cu")
		(at 247.499632 -40.903144 90)
		(property "Reference" "PD112"
			(at -3.422142 -2.350008 90)
			(unlocked yes)
			(layer "F.SilkS")
			(effects
				(font
					(size 0.7874 0.5842)
					(thickness 0.1524)
				)
				(justify left)
			)
		)
		(property "Value" ""
			(at 0 0 90)
			(layer "F.Fab")
			(effects
				(font
					(size 1.27 1.27)
				)
			)
		)
		(duplicate_pad_numbers_are_jumpers no)
		(fp_line
			(start 4.107942 -1.459992)
			(end 4.107942 1.459992)
			(stroke
				(width 0.1524)
				(type default)
			)
			(layer "F.SilkS")
		)
		(fp_line
			(start -3.400044 -1.459992)
			(end 4.107942 -1.459992)
			(stroke
				(width 0.1524)
				(type default)
			)
			(layer "F.SilkS")
		)
		(fp_line
			(start 4.107942 1.459992)
			(end -3.400044 1.459992)
			(stroke
				(width 0.1524)
				(type default)
			)
			(layer "F.SilkS")
		)
		(fp_line
			(start -3.400044 1.459992)
			(end -3.400044 -1.459992)
			(stroke
				(width 0.1524)
				(type default)
			)
			(layer "F.SilkS")
		)
		(fp_line
			(start 2.29997 -1.459992)
			(end 2.29997 1.459992)
			(stroke
				(width 0.1)
				(type default)
			)
			(layer "F.Fab")
		)
		(fp_line
			(start -2.29997 -1.459992)
			(end 2.29997 -1.459992)
			(stroke
				(width 0.1)
				(type default)
			)
			(layer "F.Fab")
		)
		(fp_line
			(start 2.29997 1.459992)
			(end -2.29997 1.459992)
			(stroke
				(width 0.1)
				(type default)
			)
			(layer "F.Fab")
		)
		(fp_line
			(start -2.29997 1.459992)
			(end -2.29997 -1.459992)
			(stroke
				(width 0.1)
				(type default)
			)
			(layer "F.Fab")
		)
		(fp_text user "+"
			(at -4.7752 -0.12065 90)
			(unlocked yes)
			(layer "F.SilkS")
			(effects
				(font
					(size 1.905 1.4224)
					(thickness 0.1524)
				)
				(justify left)
			)
		)
		(fp_text user "-"
			(at 5.245862 0.80264 270)
			(unlocked yes)
			(layer "F.SilkS")
			(effects
				(font
					(size 1.905 1.4224)
					(thickness 0.1524)
				)
				(justify left)
			)
		)
		(fp_text user "+"
			(at -4.7752 -0.12065 90)
			(unlocked yes)
			(layer "F.Fab")
			(effects
				(font
					(size 1.905 1.4224)
					(thickness 0.1524)
				)
				(justify left)
			)
		)
		(fp_text user "-"
			(at 5.4102 0.29845 270)
			(unlocked yes)
			(layer "F.Fab")
			(effects
				(font
					(size 1.905 1.4224)
					(thickness 0.1524)
				)
				(justify left)
			)
		)
		(pad "A" smd rect
			(at -1.999996 0 180)
			(size 1.7018 2.5146)
			(layers "F.Cu" "F.Mask" "F.Paste")
			(net "GND")
		)
		(pad "C" smd rect
			(at 1.999996 0 180)
			(size 1.7018 2.5146)
			(layers "F.Cu" "F.Mask" "F.Paste")
			(net "P12V_E1S_0")
		)
	)
	(footprint ""
		(layer "F.Cu")
		(at 368.241326 -43.235118 -90)
		(property "Reference" "R1423"
			(at 0 0 270)
			(layer "F.SilkS")
			(hide yes)
			(effects
				(font
					(size 1.27 1.27)
				)
			)
		)
		(property "Value" ""
			(at 0 0 270)
			(layer "F.Fab")
			(effects
				(font
					(size 1.27 1.27)
				)
			)
		)
		(duplicate_pad_numbers_are_jumpers no)
		(fp_line
			(start -0.7874 0.4064)
			(end -0.7874 -0.4064)
			(stroke
				(width 0.1524)
				(type default)
			)
			(layer "F.SilkS")
		)
		(fp_line
			(start 0.7874 0.4064)
			(end -0.7874 0.4064)
			(stroke
				(width 0.1524)
				(type default)
			)
			(layer "F.SilkS")
		)
		(fp_line
			(start -0.7874 -0.4064)
			(end 0.7874 -0.4064)
			(stroke
				(width 0.1524)
				(type default)
			)
			(layer "F.SilkS")
		)
		(fp_line
			(start 0.7874 -0.4064)
			(end 0.7874 0.4064)
			(stroke
				(width 0.1524)
				(type default)
			)
			(layer "F.SilkS")
		)
		(fp_line
			(start -0.67945 0.3048)
			(end -0.67945 -0.305054)
			(stroke
				(width 0.1)
				(type default)
			)
			(layer "F.Fab")
		)
		(fp_line
			(start -0.12065 0.3048)
			(end -0.67945 0.3048)
			(stroke
				(width 0.1)
				(type default)
			)
			(layer "F.Fab")
		)
		(fp_line
			(start 0.120396 0.3048)
			(end 0.120396 0.2794)
			(stroke
				(width 0.1)
				(type default)
			)
			(layer "F.Fab")
		)
		(fp_line
			(start 0.67945 0.3048)
			(end 0.120396 0.3048)
			(stroke
				(width 0.1)
				(type default)
			)
			(layer "F.Fab")
		)
		(fp_line
			(start -0.12065 0.2794)
			(end -0.12065 0.3048)
			(stroke
				(width 0.1)
				(type default)
			)
			(layer "F.Fab")
		)
		(fp_line
			(start 0.120396 0.2794)
			(end -0.12065 0.2794)
			(stroke
				(width 0.1)
				(type default)
			)
			(layer "F.Fab")
		)
		(fp_line
			(start -0.12065 -0.2794)
			(end 0.12065 -0.2794)
			(stroke
				(width 0.1)
				(type default)
			)
			(layer "F.Fab")
		)
		(fp_line
			(start 0.12065 -0.2794)
			(end 0.12065 -0.3048)
			(stroke
				(width 0.1)
				(type default)
			)
			(layer "F.Fab")
		)
		(fp_line
			(start 0.12065 -0.3048)
			(end 0.67945 -0.3048)
			(stroke
				(width 0.1)
				(type default)
			)
			(layer "F.Fab")
		)
		(fp_line
			(start 0.67945 -0.3048)
			(end 0.67945 0.3048)
			(stroke
				(width 0.1)
				(type default)
			)
			(layer "F.Fab")
		)
		(fp_line
			(start -0.67945 -0.305054)
			(end -0.12065 -0.305054)
			(stroke
				(width 0.1)
				(type default)
			)
			(layer "F.Fab")
		)
		(fp_line
			(start -0.12065 -0.305054)
			(end -0.12065 -0.2794)
			(stroke
				(width 0.1)
				(type default)
			)
			(layer "F.Fab")
		)
		(pad "1" smd circle
			(at -0.40005 0 270)
			(size 0 0)
			(layers "F.Cu" "F.Mask" "F.Paste")
			(net "UART_CPU0_SCM_UART1_RX")
		)
		(pad "2" smd circle
			(at 0.40005 0 270)
			(size 0 0)
			(layers "F.Cu" "F.Mask" "F.Paste")
			(net "UART_CPU0_SCM_UART1_R_RX")
		)
	)
)
